(kicad_pcb
	(version 20260206)
	(generator "pcbnew")
	(generator_version "10.0")
	(general
		(thickness 1.6)
		(legacy_teardrops no)
	)
	(paper "A4")
	(title_block
		(title "03242023_DA0F0TMBIJ0_F0T_Motherboard_J_brd_V01_OCP.brd")
		(comment 1 "Grand Teton / footprints 4071-4077 of 6105")
	)
	(layers
		(0 "F.Cu" signal "TOP")
		(4 "In1.Cu" signal "GND")
		(6 "In2.Cu" signal "IN1")
		(8 "In3.Cu" signal "GND1")
		(10 "In4.Cu" signal "IN2")
		(12 "In5.Cu" signal "GND2")
		(14 "In6.Cu" signal "IN3")
		(16 "In7.Cu" signal "GND3")
		(18 "In8.Cu" signal "VCC")
		(20 "In9.Cu" signal "VCC1")
		(22 "In10.Cu" signal "GND4")
		(24 "In11.Cu" signal "IN4")
		(26 "In12.Cu" signal "GND5")
		(28 "In13.Cu" signal "IN5")
		(30 "In14.Cu" signal "GND6")
		(32 "In15.Cu" signal "IN6")
		(34 "In16.Cu" signal "GND7")
		(2 "B.Cu" signal "BOTTOM")
		(9 "F.Adhes" user "F.Adhesive")
		(11 "B.Adhes" user "B.Adhesive")
		(13 "F.Paste" user "Package Geometry/Pastemask Top")
		(15 "B.Paste" user "Package Geometry/Pastemask Bottom")
		(5 "F.SilkS" user "Ref Des/Silkscreen Top")
		(7 "B.SilkS" user "Ref Des/Silkscreen Bottom")
		(1 "F.Mask" user "Board Geometry/Soldermask Top")
		(3 "B.Mask" user "Board Geometry/Soldermask Bottom")
		(17 "Dwgs.User" user "User.Drawings")
		(19 "Cmts.User" user "User.Comments")
		(21 "Eco1.User" user "User.Eco1")
		(23 "Eco2.User" user "User.Eco2")
		(25 "Edge.Cuts" user "Board Geometry/Outline")
		(27 "Margin" user)
		(31 "F.CrtYd" user "Package Geometry/Place Bound Top")
		(29 "B.CrtYd" user "Package Geometry/Place Bound Bottom")
		(35 "F.Fab" user "Ref Des/Assembly Top")
		(33 "B.Fab" user "Ref Des/Assembly Bottom")
	)
	(footprint ""
		(layer "F.Cu")
		(at 20.60956 -70.814692)
		(property "Reference" "R3136"
			(at 0 0 0)
			(layer "F.SilkS")
			(hide yes)
			(effects
				(font
					(size 1.27 1.27)
				)
			)
		)
		(property "Value" ""
			(at 0 0 0)
			(layer "F.Fab")
			(effects
				(font
					(size 1.27 1.27)
				)
			)
		)
		(duplicate_pad_numbers_are_jumpers no)
		(fp_line
			(start -0.7874 -0.4064)
			(end 0.7874 -0.4064)
			(stroke
				(width 0.1524)
				(type default)
			)
			(layer "F.SilkS")
		)
		(fp_line
			(start -0.7874 0.4064)
			(end -0.7874 -0.4064)
			(stroke
				(width 0.1524)
				(type default)
			)
			(layer "F.SilkS")
		)
		(fp_line
			(start 0.7874 -0.4064)
			(end 0.7874 0.4064)
			(stroke
				(width 0.1524)
				(type default)
			)
			(layer "F.SilkS")
		)
		(fp_line
			(start 0.7874 0.4064)
			(end -0.7874 0.4064)
			(stroke
				(width 0.1524)
				(type default)
			)
			(layer "F.SilkS")
		)
		(fp_line
			(start -0.67945 -0.305054)
			(end -0.12065 -0.305054)
			(stroke
				(width 0.1)
				(type default)
			)
			(layer "F.Fab")
		)
		(fp_line
			(start -0.67945 0.3048)
			(end -0.67945 -0.305054)
			(stroke
				(width 0.1)
				(type default)
			)
			(layer "F.Fab")
		)
		(fp_line
			(start -0.12065 -0.305054)
			(end -0.12065 -0.2794)
			(stroke
				(width 0.1)
				(type default)
			)
			(layer "F.Fab")
		)
		(fp_line
			(start -0.12065 -0.2794)
			(end 0.12065 -0.2794)
			(stroke
				(width 0.1)
				(type default)
			)
			(layer "F.Fab")
		)
		(fp_line
			(start -0.12065 0.2794)
			(end -0.12065 0.3048)
			(stroke
				(width 0.1)
				(type default)
			)
			(layer "F.Fab")
		)
		(fp_line
			(start -0.12065 0.3048)
			(end -0.67945 0.3048)
			(stroke
				(width 0.1)
				(type default)
			)
			(layer "F.Fab")
		)
		(fp_line
			(start 0.120396 0.2794)
			(end -0.12065 0.2794)
			(stroke
				(width 0.1)
				(type default)
			)
			(layer "F.Fab")
		)
		(fp_line
			(start 0.120396 0.3048)
			(end 0.120396 0.2794)
			(stroke
				(width 0.1)
				(type default)
			)
			(layer "F.Fab")
		)
		(fp_line
			(start 0.12065 -0.3048)
			(end 0.67945 -0.3048)
			(stroke
				(width 0.1)
				(type default)
			)
			(layer "F.Fab")
		)
		(fp_line
			(start 0.12065 -0.2794)
			(end 0.12065 -0.3048)
			(stroke
				(width 0.1)
				(type default)
			)
			(layer "F.Fab")
		)
		(fp_line
			(start 0.67945 -0.3048)
			(end 0.67945 0.3048)
			(stroke
				(width 0.1)
				(type default)
			)
			(layer "F.Fab")
		)
		(fp_line
			(start 0.67945 0.3048)
			(end 0.120396 0.3048)
			(stroke
				(width 0.1)
				(type default)
			)
			(layer "F.Fab")
		)
		(pad "1" smd circle
			(at -0.40005 0)
			(size 0 0)
			(layers "F.Cu" "F.Mask" "F.Paste")
			(net "P3V3_AUX")
		)
		(pad "2" smd circle
			(at 0.40005 0)
			(size 0 0)
			(layers "F.Cu" "F.Mask" "F.Paste")
			(net "OCP_V3_2_PRSNT3_R_N")
		)
	)
	(footprint ""
		(layer "F.Cu")
		(at 395.90345 -402.371052 -90)
		(property "Reference" "C951"
			(at 0 0 270)
			(layer "F.SilkS")
			(hide yes)
			(effects
				(font
					(size 1.27 1.27)
				)
			)
		)
		(property "Value" ""
			(at 0 0 270)
			(layer "F.Fab")
			(effects
				(font
					(size 1.27 1.27)
				)
			)
		)
		(duplicate_pad_numbers_are_jumpers no)
		(fp_line
			(start -0.299974 0.150114)
			(end -0.299974 -0.150114)
			(stroke
				(width 0.1)
				(type default)
			)
			(layer "F.Fab")
		)
		(fp_line
			(start 0.299974 0.150114)
			(end -0.299974 0.150114)
			(stroke
				(width 0.1)
				(type default)
			)
			(layer "F.Fab")
		)
		(fp_line
			(start -0.299974 -0.150114)
			(end 0.299974 -0.150114)
			(stroke
				(width 0.1)
				(type default)
			)
			(layer "F.Fab")
		)
		(fp_line
			(start 0.299974 -0.150114)
			(end 0.299974 0.150114)
			(stroke
				(width 0.1)
				(type default)
			)
			(layer "F.Fab")
		)
		(pad "1" smd rect
			(at -0.2667 0 270)
			(size 0.3048 0.381)
			(layers "F.Cu" "F.Mask" "F.Paste")
			(net "P5E_CPU0_PE2_TX_C_DP<7>")
		)
		(pad "2" smd rect
			(at 0.2667 0 270)
			(size 0.3048 0.381)
			(layers "F.Cu" "F.Mask" "F.Paste")
			(net "P5E_CPU0_PE2_TX_DP<7>")
		)
	)
	(footprint ""
		(layer "F.Cu")
		(at 437.542432 -27.275536 90)
		(property "Reference" "PR3841"
			(at 0 0 90)
			(layer "F.SilkS")
			(hide yes)
			(effects
				(font
					(size 1.27 1.27)
				)
			)
		)
		(property "Value" ""
			(at 0 0 90)
			(layer "F.Fab")
			(effects
				(font
					(size 1.27 1.27)
				)
			)
		)
		(duplicate_pad_numbers_are_jumpers no)
		(fp_line
			(start 0.7874 -0.4064)
			(end 0.7874 0.4064)
			(stroke
				(width 0.1524)
				(type default)
			)
			(layer "F.SilkS")
		)
		(fp_line
			(start -0.7874 -0.4064)
			(end 0.7874 -0.4064)
			(stroke
				(width 0.1524)
				(type default)
			)
			(layer "F.SilkS")
		)
		(fp_line
			(start 0.7874 0.4064)
			(end -0.7874 0.4064)
			(stroke
				(width 0.1524)
				(type default)
			)
			(layer "F.SilkS")
		)
		(fp_line
			(start -0.7874 0.4064)
			(end -0.7874 -0.4064)
			(stroke
				(width 0.1524)
				(type default)
			)
			(layer "F.SilkS")
		)
		(fp_line
			(start -0.12065 -0.305054)
			(end -0.12065 -0.2794)
			(stroke
				(width 0.1)
				(type default)
			)
			(layer "F.Fab")
		)
		(fp_line
			(start -0.67945 -0.305054)
			(end -0.12065 -0.305054)
			(stroke
				(width 0.1)
				(type default)
			)
			(layer "F.Fab")
		)
		(fp_line
			(start 0.67945 -0.3048)
			(end 0.67945 0.3048)
			(stroke
				(width 0.1)
				(type default)
			)
			(layer "F.Fab")
		)
		(fp_line
			(start 0.12065 -0.3048)
			(end 0.67945 -0.3048)
			(stroke
				(width 0.1)
				(type default)
			)
			(layer "F.Fab")
		)
		(fp_line
			(start 0.12065 -0.2794)
			(end 0.12065 -0.3048)
			(stroke
				(width 0.1)
				(type default)
			)
			(layer "F.Fab")
		)
		(fp_line
			(start -0.12065 -0.2794)
			(end 0.12065 -0.2794)
			(stroke
				(width 0.1)
				(type default)
			)
			(layer "F.Fab")
		)
		(fp_line
			(start 0.120396 0.2794)
			(end -0.12065 0.2794)
			(stroke
				(width 0.1)
				(type default)
			)
			(layer "F.Fab")
		)
		(fp_line
			(start -0.12065 0.2794)
			(end -0.12065 0.3048)
			(stroke
				(width 0.1)
				(type default)
			)
			(layer "F.Fab")
		)
		(fp_line
			(start 0.67945 0.3048)
			(end 0.120396 0.3048)
			(stroke
				(width 0.1)
				(type default)
			)
			(layer "F.Fab")
		)
		(fp_line
			(start 0.120396 0.3048)
			(end 0.120396 0.2794)
			(stroke
				(width 0.1)
				(type default)
			)
			(layer "F.Fab")
		)
		(fp_line
			(start -0.12065 0.3048)
			(end -0.67945 0.3048)
			(stroke
				(width 0.1)
				(type default)
			)
			(layer "F.Fab")
		)
		(fp_line
			(start -0.67945 0.3048)
			(end -0.67945 -0.305054)
			(stroke
				(width 0.1)
				(type default)
			)
			(layer "F.Fab")
		)
		(pad "1" smd circle
			(at -0.40005 0 90)
			(size 0 0)
			(layers "F.Cu" "F.Mask" "F.Paste")
			(net "P12V_AUX")
		)
		(pad "2" smd circle
			(at 0.40005 0 90)
			(size 0 0)
			(layers "F.Cu" "F.Mask" "F.Paste")
			(net "P12V_OCP_OV_FB_1")
		)
	)
	(footprint ""
		(layer "F.Cu")
		(at 455.434192 -38.938962)
		(property "Reference" "U75"
			(at -1.778 -1.819148 0)
			(unlocked yes)
			(layer "F.SilkS")
			(effects
				(font
					(size 0.7874 0.5842)
					(thickness 0.1524)
				)
				(justify left)
			)
		)
		(property "Value" ""
			(at 0 0 0)
			(layer "F.Fab")
			(effects
				(font
					(size 1.27 1.27)
				)
			)
		)
		(duplicate_pad_numbers_are_jumpers no)
		(fp_line
			(start -1.695958 -1.124966)
			(end 1.695958 -1.124966)
			(stroke
				(width 0.1524)
				(type default)
			)
			(layer "F.SilkS")
		)
		(fp_line
			(start -1.695958 1.124966)
			(end -1.695958 -1.124966)
			(stroke
				(width 0.1524)
				(type default)
			)
			(layer "F.SilkS")
		)
		(fp_line
			(start 1.695958 -1.124966)
			(end 1.695958 1.124966)
			(stroke
				(width 0.1524)
				(type default)
			)
			(layer "F.SilkS")
		)
		(fp_line
			(start 1.695958 1.124966)
			(end -1.695958 1.124966)
			(stroke
				(width 0.1524)
				(type default)
			)
			(layer "F.SilkS")
		)
		(fp_poly
			(pts
				(xy -2.4892 -0.340106) (xy -2.4892 -0.959866) (xy -1.86944 -0.649986)
			)
			(stroke
				(width 0)
				(type default)
			)
			(fill yes)
			(layer "F.SilkS")
		)
		(fp_line
			(start -0.674878 -1.124966)
			(end 0.674878 -1.124966)
			(stroke
				(width 0.1)
				(type default)
			)
			(layer "F.Fab")
		)
		(fp_line
			(start -0.674878 1.124966)
			(end -0.674878 -1.124966)
			(stroke
				(width 0.1)
				(type default)
			)
			(layer "F.Fab")
		)
		(fp_line
			(start 0.674878 -1.124966)
			(end 0.674878 1.124966)
			(stroke
				(width 0.1)
				(type default)
			)
			(layer "F.Fab")
		)
		(fp_line
			(start 0.674878 1.124966)
			(end -0.674878 1.124966)
			(stroke
				(width 0.1)
				(type default)
			)
			(layer "F.Fab")
		)
		(fp_poly
			(pts
				(xy -2.4892 -0.959866) (xy -1.86944 -0.649986) (xy -2.4892 -0.340106)
			)
			(stroke
				(width 0)
				(type default)
			)
			(fill yes)
			(layer "F.Fab")
		)
		(pad "1" smd rect
			(at -0.94488 -0.649986 90)
			(size 0.3556 1.2446)
			(layers "F.Cu" "F.Mask" "F.Paste")
			(net "Net_1914")
		)
		(pad "2" smd rect
			(at -0.94488 0 90)
			(size 0.3556 1.2446)
			(layers "F.Cu" "F.Mask" "F.Paste")
			(net "RST_HP_OCP_V3_1_N")
		)
		(pad "3" smd rect
			(at -0.94488 0.649986 90)
			(size 0.3556 1.2446)
			(layers "F.Cu" "F.Mask" "F.Paste")
			(net "GND")
		)
		(pad "4" smd rect
			(at 0.94488 0.649986 90)
			(size 0.3556 1.2446)
			(layers "F.Cu" "F.Mask" "F.Paste")
			(net "RST_OCP_V3_1_BUF_N")
		)
		(pad "5" smd rect
			(at 0.94488 -0.649986 90)
			(size 0.3556 1.2446)
			(layers "F.Cu" "F.Mask" "F.Paste")
			(net "P3V3_AUX")
		)
	)
	(footprint ""
		(layer "F.Cu")
		(at 346.964254 -24.66213 90)
		(property "Reference" "R1025"
			(at 0 0 90)
			(layer "F.SilkS")
			(hide yes)
			(effects
				(font
					(size 1.27 1.27)
				)
			)
		)
		(property "Value" ""
			(at 0 0 90)
			(layer "F.Fab")
			(effects
				(font
					(size 1.27 1.27)
				)
			)
		)
		(duplicate_pad_numbers_are_jumpers no)
		(fp_line
			(start 0.7874 -0.4064)
			(end 0.7874 0.4064)
			(stroke
				(width 0.1524)
				(type default)
			)
			(layer "F.SilkS")
		)
		(fp_line
			(start -0.7874 -0.4064)
			(end 0.7874 -0.4064)
			(stroke
				(width 0.1524)
				(type default)
			)
			(layer "F.SilkS")
		)
		(fp_line
			(start 0.7874 0.4064)
			(end -0.7874 0.4064)
			(stroke
				(width 0.1524)
				(type default)
			)
			(layer "F.SilkS")
		)
		(fp_line
			(start -0.7874 0.4064)
			(end -0.7874 -0.4064)
			(stroke
				(width 0.1524)
				(type default)
			)
			(layer "F.SilkS")
		)
		(fp_line
			(start -0.12065 -0.305054)
			(end -0.12065 -0.2794)
			(stroke
				(width 0.1)
				(type default)
			)
			(layer "F.Fab")
		)
		(fp_line
			(start -0.67945 -0.305054)
			(end -0.12065 -0.305054)
			(stroke
				(width 0.1)
				(type default)
			)
			(layer "F.Fab")
		)
		(fp_line
			(start 0.67945 -0.3048)
			(end 0.67945 0.3048)
			(stroke
				(width 0.1)
				(type default)
			)
			(layer "F.Fab")
		)
		(fp_line
			(start 0.12065 -0.3048)
			(end 0.67945 -0.3048)
			(stroke
				(width 0.1)
				(type default)
			)
			(layer "F.Fab")
		)
		(fp_line
			(start 0.12065 -0.2794)
			(end 0.12065 -0.3048)
			(stroke
				(width 0.1)
				(type default)
			)
			(layer "F.Fab")
		)
		(fp_line
			(start -0.12065 -0.2794)
			(end 0.12065 -0.2794)
			(stroke
				(width 0.1)
				(type default)
			)
			(layer "F.Fab")
		)
		(fp_line
			(start 0.120396 0.2794)
			(end -0.12065 0.2794)
			(stroke
				(width 0.1)
				(type default)
			)
			(layer "F.Fab")
		)
		(fp_line
			(start -0.12065 0.2794)
			(end -0.12065 0.3048)
			(stroke
				(width 0.1)
				(type default)
			)
			(layer "F.Fab")
		)
		(fp_line
			(start 0.67945 0.3048)
			(end 0.120396 0.3048)
			(stroke
				(width 0.1)
				(type default)
			)
			(layer "F.Fab")
		)
		(fp_line
			(start 0.120396 0.3048)
			(end 0.120396 0.2794)
			(stroke
				(width 0.1)
				(type default)
			)
			(layer "F.Fab")
		)
		(fp_line
			(start -0.12065 0.3048)
			(end -0.67945 0.3048)
			(stroke
				(width 0.1)
				(type default)
			)
			(layer "F.Fab")
		)
		(fp_line
			(start -0.67945 0.3048)
			(end -0.67945 -0.305054)
			(stroke
				(width 0.1)
				(type default)
			)
			(layer "F.Fab")
		)
		(pad "1" smd circle
			(at -0.40005 0 90)
			(size 0 0)
			(layers "F.Cu" "F.Mask" "F.Paste")
			(net "JTAG_DBP_CPU_GTL_TCK")
		)
		(pad "2" smd circle
			(at 0.40005 0 90)
			(size 0 0)
			(layers "F.Cu" "F.Mask" "F.Paste")
			(net "GND")
		)
	)
	(footprint ""
		(layer "F.Cu")
		(at 252.961648 -54.161182 180)
		(property "Reference" "PR3954"
			(at 0 0 180)
			(layer "F.SilkS")
			(hide yes)
			(effects
				(font
					(size 1.27 1.27)
				)
			)
		)
		(property "Value" ""
			(at 0 0 180)
			(layer "F.Fab")
			(effects
				(font
					(size 1.27 1.27)
				)
			)
		)
		(duplicate_pad_numbers_are_jumpers no)
		(fp_line
			(start 0.7874 0.4064)
			(end -0.7874 0.4064)
			(stroke
				(width 0.1524)
				(type default)
			)
			(layer "F.SilkS")
		)
		(fp_line
			(start 0.7874 -0.4064)
			(end 0.7874 0.4064)
			(stroke
				(width 0.1524)
				(type default)
			)
			(layer "F.SilkS")
		)
		(fp_line
			(start -0.7874 0.4064)
			(end -0.7874 -0.4064)
			(stroke
				(width 0.1524)
				(type default)
			)
			(layer "F.SilkS")
		)
		(fp_line
			(start -0.7874 -0.4064)
			(end 0.7874 -0.4064)
			(stroke
				(width 0.1524)
				(type default)
			)
			(layer "F.SilkS")
		)
		(fp_line
			(start 0.67945 0.3048)
			(end 0.120396 0.3048)
			(stroke
				(width 0.1)
				(type default)
			)
			(layer "F.Fab")
		)
		(fp_line
			(start 0.67945 -0.3048)
			(end 0.67945 0.3048)
			(stroke
				(width 0.1)
				(type default)
			)
			(layer "F.Fab")
		)
		(fp_line
			(start 0.12065 -0.2794)
			(end 0.12065 -0.3048)
			(stroke
				(width 0.1)
				(type default)
			)
			(layer "F.Fab")
		)
		(fp_line
			(start 0.12065 -0.3048)
			(end 0.67945 -0.3048)
			(stroke
				(width 0.1)
				(type default)
			)
			(layer "F.Fab")
		)
		(fp_line
			(start 0.120396 0.3048)
			(end 0.120396 0.2794)
			(stroke
				(width 0.1)
				(type default)
			)
			(layer "F.Fab")
		)
		(fp_line
			(start 0.120396 0.2794)
			(end -0.12065 0.2794)
			(stroke
				(width 0.1)
				(type default)
			)
			(layer "F.Fab")
		)
		(fp_line
			(start -0.12065 0.3048)
			(end -0.67945 0.3048)
			(stroke
				(width 0.1)
				(type default)
			)
			(layer "F.Fab")
		)
		(fp_line
			(start -0.12065 0.2794)
			(end -0.12065 0.3048)
			(stroke
				(width 0.1)
				(type default)
			)
			(layer "F.Fab")
		)
		(fp_line
			(start -0.12065 -0.2794)
			(end 0.12065 -0.2794)
			(stroke
				(width 0.1)
				(type default)
			)
			(layer "F.Fab")
		)
		(fp_line
			(start -0.12065 -0.305054)
			(end -0.12065 -0.2794)
			(stroke
				(width 0.1)
				(type default)
			)
			(layer "F.Fab")
		)
		(fp_line
			(start -0.67945 0.3048)
			(end -0.67945 -0.305054)
			(stroke
				(width 0.1)
				(type default)
			)
			(layer "F.Fab")
		)
		(fp_line
			(start -0.67945 -0.305054)
			(end -0.12065 -0.305054)
			(stroke
				(width 0.1)
				(type default)
			)
			(layer "F.Fab")
		)
		(pad "1" smd circle
			(at -0.40005 0 180)
			(size 0 0)
			(layers "F.Cu" "F.Mask" "F.Paste")
			(net "P12V_E1S_OV_FB_0")
		)
		(pad "2" smd circle
			(at 0.40005 0 180)
			(size 0 0)
			(layers "F.Cu" "F.Mask" "F.Paste")
			(net "GND")
		)
	)
	(footprint ""
		(layer "F.Cu")
		(at 309.01894 -56.045608 90)
		(property "Reference" "R147"
			(at 0 0 90)
			(layer "F.SilkS")
			(hide yes)
			(effects
				(font
					(size 1.27 1.27)
				)
			)
		)
		(property "Value" ""
			(at 0 0 90)
			(layer "F.Fab")
			(effects
				(font
					(size 1.27 1.27)
				)
			)
		)
		(duplicate_pad_numbers_are_jumpers no)
		(fp_line
			(start 0.7874 -0.4064)
			(end 0.7874 0.4064)
			(stroke
				(width 0.1524)
				(type default)
			)
			(layer "F.SilkS")
		)
		(fp_line
			(start -0.7874 -0.4064)
			(end 0.7874 -0.4064)
			(stroke
				(width 0.1524)
				(type default)
			)
			(layer "F.SilkS")
		)
		(fp_line
			(start 0.7874 0.4064)
			(end -0.7874 0.4064)
			(stroke
				(width 0.1524)
				(type default)
			)
			(layer "F.SilkS")
		)
		(fp_line
			(start -0.7874 0.4064)
			(end -0.7874 -0.4064)
			(stroke
				(width 0.1524)
				(type default)
			)
			(layer "F.SilkS")
		)
		(fp_line
			(start -0.12065 -0.305054)
			(end -0.12065 -0.2794)
			(stroke
				(width 0.1)
				(type default)
			)
			(layer "F.Fab")
		)
		(fp_line
			(start -0.67945 -0.305054)
			(end -0.12065 -0.305054)
			(stroke
				(width 0.1)
				(type default)
			)
			(layer "F.Fab")
		)
		(fp_line
			(start 0.67945 -0.3048)
			(end 0.67945 0.3048)
			(stroke
				(width 0.1)
				(type default)
			)
			(layer "F.Fab")
		)
		(fp_line
			(start 0.12065 -0.3048)
			(end 0.67945 -0.3048)
			(stroke
				(width 0.1)
				(type default)
			)
			(layer "F.Fab")
		)
		(fp_line
			(start 0.12065 -0.2794)
			(end 0.12065 -0.3048)
			(stroke
				(width 0.1)
				(type default)
			)
			(layer "F.Fab")
		)
		(fp_line
			(start -0.12065 -0.2794)
			(end 0.12065 -0.2794)
			(stroke
				(width 0.1)
				(type default)
			)
			(layer "F.Fab")
		)
		(fp_line
			(start 0.120396 0.2794)
			(end -0.12065 0.2794)
			(stroke
				(width 0.1)
				(type default)
			)
			(layer "F.Fab")
		)
		(fp_line
			(start -0.12065 0.2794)
			(end -0.12065 0.3048)
			(stroke
				(width 0.1)
				(type default)
			)
			(layer "F.Fab")
		)
		(fp_line
			(start 0.67945 0.3048)
			(end 0.120396 0.3048)
			(stroke
				(width 0.1)
				(type default)
			)
			(layer "F.Fab")
		)
		(fp_line
			(start 0.120396 0.3048)
			(end 0.120396 0.2794)
			(stroke
				(width 0.1)
				(type default)
			)
			(layer "F.Fab")
		)
		(fp_line
			(start -0.12065 0.3048)
			(end -0.67945 0.3048)
			(stroke
				(width 0.1)
				(type default)
			)
			(layer "F.Fab")
		)
		(fp_line
			(start -0.67945 0.3048)
			(end -0.67945 -0.305054)
			(stroke
				(width 0.1)
				(type default)
			)
			(layer "F.Fab")
		)
		(pad "1" smd circle
			(at -0.40005 0 90)
			(size 0 0)
			(layers "F.Cu" "F.Mask" "F.Paste")
			(net "PECI_PCH_R")
		)
		(pad "2" smd circle
			(at 0.40005 0 90)
			(size 0 0)
			(layers "F.Cu" "F.Mask" "F.Paste")
			(net "GND")
		)
	)
)
